(kicad_pcb
	(version 20260206)
	(generator "pcbnew")
	(generator_version "10.0")
	(general
		(thickness 1.6)
		(legacy_teardrops no)
	)
	(paper "A4")
	(title_block
		(title "Wiwynn_Tioga_Pass_MB.brd")
		(comment 1 "Tioga Pass / footprints 803-807 of 4770")
	)
	(layers
		(0 "F.Cu" signal "TOP")
		(4 "In1.Cu" signal "L2GND")
		(6 "In2.Cu" signal "L3")
		(8 "In3.Cu" signal "L4GND")
		(10 "In4.Cu" signal "L5")
		(12 "In5.Cu" signal "L6GND")
		(14 "In6.Cu" signal "L7VCC")
		(16 "In7.Cu" signal "L8VCC")
		(18 "In8.Cu" signal "L9GND")
		(20 "In9.Cu" signal "L10")
		(22 "In10.Cu" signal "L11GND")
		(24 "In11.Cu" signal "L12")
		(26 "In12.Cu" signal "L13GND")
		(2 "B.Cu" signal "BOTTOM")
		(9 "F.Adhes" user "F.Adhesive")
		(11 "B.Adhes" user "B.Adhesive")
		(13 "F.Paste" user "Package Geometry/Pastemask Top")
		(15 "B.Paste" user "Package Geometry/Pastemask Bottom")
		(5 "F.SilkS" user "Ref Des/Silkscreen Top")
		(7 "B.SilkS" user "Ref Des/Silkscreen Bottom")
		(1 "F.Mask" user "Board Geometry/Soldermask Top")
		(3 "B.Mask" user "Board Geometry/Soldermask Bottom")
		(17 "Dwgs.User" user "User.Drawings")
		(19 "Cmts.User" user "User.Comments")
		(21 "Eco1.User" user "User.Eco1")
		(23 "Eco2.User" user "User.Eco2")
		(25 "Edge.Cuts" user "Board Geometry/Outline")
		(27 "Margin" user)
		(31 "F.CrtYd" user "Package Geometry/Place Bound Top")
		(29 "B.CrtYd" user "Package Geometry/Place Bound Bottom")
		(35 "F.Fab" user "Ref Des/Assembly Top")
		(33 "B.Fab" user "Ref Des/Assembly Bottom")
	)
	(footprint ""
		(layer "F.Cu")
		(at 277.15972 -83.86064)
		(property "Reference" "R6D1"
			(at 0 0 0)
			(layer "F.SilkS")
			(hide yes)
			(effects
				(font
					(size 1.27 1.27)
				)
			)
		)
		(property "Value" ""
			(at 0 0 0)
			(layer "F.Fab")
			(effects
				(font
					(size 1.27 1.27)
				)
			)
		)
		(duplicate_pad_numbers_are_jumpers no)
		(fp_poly
			(pts
				(xy -0.2794 -0.1016) (xy 0.2794 -0.1016) (xy 0.2794 0.9906) (xy -0.2794 0.9906)
			)
			(stroke
				(width 0)
				(type default)
			)
			(fill no)
			(layer "F.CrtYd")
		)
		(fp_line
			(start -0.2794 -0.1016)
			(end -0.2794 0.9906)
			(stroke
				(width 0.1)
				(type default)
			)
			(layer "F.Fab")
		)
		(fp_line
			(start -0.2794 0.9906)
			(end 0.2794 0.9906)
			(stroke
				(width 0.1)
				(type default)
			)
			(layer "F.Fab")
		)
		(fp_line
			(start 0.2794 -0.1016)
			(end -0.2794 -0.1016)
			(stroke
				(width 0.1)
				(type default)
			)
			(layer "F.Fab")
		)
		(fp_line
			(start 0.2794 0.9906)
			(end 0.2794 -0.1016)
			(stroke
				(width 0.1)
				(type default)
			)
			(layer "F.Fab")
		)
		(pad "1" smd rect
			(at 0 0)
			(size 0.508 0.508)
			(layers "F.Cu" "F.Mask" "F.Paste")
			(net "A_CPU0_DEF_RCOMP2")
		)
		(pad "2" smd rect
			(at 0 0.889)
			(size 0.508 0.508)
			(layers "F.Cu" "F.Mask" "F.Paste")
			(net "GND")
		)
		(zone
			(layer "F.Cu")
			(hatch none 0.5)
			(connect_pads
				(clearance 0)
			)
			(min_thickness 0.25)
			(keepout
				(tracks allowed)
				(vias not_allowed)
				(pads allowed)
				(copperpour not_allowed)
				(footprints allowed)
			)
			(placement
				(enabled no)
				(sheetname "")
			)
			(fill
				(thermal_gap 0.5)
				(thermal_bridge_width 0.5)
				(island_removal_mode 0)
			)
			(polygon
				(pts
					(xy 276.90572 -83.60664) (xy 277.41372 -83.60664) (xy 277.41372 -83.22564) (xy 276.90572 -83.22564)
				)
			)
		)
		(zone
			(layer "F.Cu")
			(hatch none 0.5)
			(connect_pads
				(clearance 0)
			)
			(min_thickness 0.25)
			(keepout
				(tracks not_allowed)
				(vias allowed)
				(pads allowed)
				(copperpour not_allowed)
				(footprints allowed)
			)
			(placement
				(enabled no)
				(sheetname "")
			)
			(fill
				(thermal_gap 0.5)
				(thermal_bridge_width 0.5)
				(island_removal_mode 0)
			)
			(polygon
				(pts
					(xy 276.90572 -83.22564) (xy 277.41372 -83.22564) (xy 277.41372 -83.60664) (xy 276.90572 -83.60664)
				)
			)
		)
	)
	(footprint ""
		(layer "F.Cu")
		(at 34.417 10.7315 -90)
		(property "Reference" "T1P30"
			(at 0 0 270)
			(layer "F.SilkS")
			(hide yes)
			(effects
				(font
					(size 1.27 1.27)
				)
			)
		)
		(property "Value" "*"
			(at 0 -3.44805 270)
			(unlocked yes)
			(layer "F.Fab")
			(hide yes)
			(effects
				(font
					(size 0.889 0.889)
					(thickness 0.1524)
				)
			)
		)
		(property "Device Type" "TPAD-SE-2P-GP_DISCRET-GA1-TPADA"
			(at 0 -4.97205 270)
			(unlocked yes)
			(layer "F.Fab")
			(hide yes)
			(effects
				(font
					(size 0.889 0.889)
					(thickness 0.1524)
				)
			)
		)
		(duplicate_pad_numbers_are_jumpers no)
		(fp_line
			(start -1.016 2.286)
			(end -1.016 -2.286)
			(stroke
				(width 0.1524)
				(type default)
			)
			(layer "F.SilkS")
		)
		(fp_line
			(start 1.016 2.286)
			(end -1.016 2.286)
			(stroke
				(width 0.1524)
				(type default)
			)
			(layer "F.SilkS")
		)
		(fp_line
			(start -1.016 -2.286)
			(end 1.016 -2.286)
			(stroke
				(width 0.1524)
				(type default)
			)
			(layer "F.SilkS")
		)
		(fp_line
			(start 1.016 -2.286)
			(end 1.016 2.286)
			(stroke
				(width 0.1524)
				(type default)
			)
			(layer "F.SilkS")
		)
		(fp_rect
			(start -1.27 2.54)
			(end 1.27 -2.54)
			(stroke
				(width 0)
				(type default)
			)
			(fill no)
			(layer "F.CrtYd")
		)
		(fp_rect
			(start -1.27 2.54)
			(end 1.27 -2.54)
			(stroke
				(width 0)
				(type default)
			)
			(fill no)
			(layer "F.Fab")
		)
		(pad "1" thru_hole circle
			(at 0 -1.27 270)
			(size 1.524 1.524)
			(drill 0.9144)
			(layers "*.Cu" "*.Mask")
			(remove_unused_layers no)
			(net "L14_40OHM_6INCH")
			(clearance -0.0508)
			(thermal_gap 0.127)
			(padstack
				(mode front_inner_back)
				(layer "Inner"
					(shape circle)
					(size 1.1684 1.1684)
					(clearance 0.127)
				)
				(layer "B.Cu"
					(shape circle)
					(size 1.524 1.524)
					(clearance -0.0508)
				)
			)
		)
		(pad "GND1" thru_hole rect
			(at 0 1.27 270)
			(size 1.524 1.524)
			(drill 0.9144)
			(layers "*.Cu" "*.Mask")
			(remove_unused_layers no)
			(net "GND")
			(clearance -0.0508)
			(thermal_gap 0.127)
			(padstack
				(mode front_inner_back)
				(layer "Inner"
					(shape circle)
					(size 1.1684 1.1684)
					(clearance 0.127)
				)
				(layer "B.Cu"
					(shape rect)
					(size 1.524 1.524)
					(clearance -0.0508)
				)
			)
		)
	)
	(footprint ""
		(layer "F.Cu")
		(at 308.874414 -164.908992 90)
		(property "Reference" "T1D22"
			(at 0 0 90)
			(layer "F.SilkS")
			(hide yes)
			(effects
				(font
					(size 1.27 1.27)
				)
			)
		)
		(property "Value" "*"
			(at -3.4036 -4.46405 90)
			(unlocked yes)
			(layer "F.Fab")
			(hide yes)
			(effects
				(font
					(size 0.889 0.889)
					(thickness 0.1524)
				)
			)
		)
		(property "Device Type" "TEST-PAD-12P-1-GP-U_DISCRET-GBA"
			(at -3.4036 -5.98805 90)
			(unlocked yes)
			(layer "F.Fab")
			(hide yes)
			(effects
				(font
					(size 0.889 0.889)
					(thickness 0.1524)
				)
			)
		)
		(duplicate_pad_numbers_are_jumpers no)
		(fp_line
			(start 2.3622 -4.826)
			(end 2.3622 3.4798)
			(stroke
				(width 0.1524)
				(type default)
			)
			(layer "F.SilkS")
		)
		(fp_line
			(start -2.3876 -4.826)
			(end 2.3622 -4.826)
			(stroke
				(width 0.1524)
				(type default)
			)
			(layer "F.SilkS")
		)
		(fp_line
			(start 2.3622 3.4798)
			(end -2.3876 3.4798)
			(stroke
				(width 0.1524)
				(type default)
			)
			(layer "F.SilkS")
		)
		(fp_line
			(start -2.3876 3.4798)
			(end -2.3876 -4.826)
			(stroke
				(width 0.1524)
				(type default)
			)
			(layer "F.SilkS")
		)
		(fp_rect
			(start -2.6416 3.7338)
			(end 2.6162 -5.08)
			(stroke
				(width 0)
				(type default)
			)
			(fill no)
			(layer "F.CrtYd")
		)
		(fp_rect
			(start -2.6416 3.7338)
			(end 2.6162 -5.08)
			(stroke
				(width 0)
				(type default)
			)
			(fill no)
			(layer "F.Fab")
		)
		(pad "1" smd circle
			(at 0.496824 -1.301496 90)
			(size 0.6604 0.6604)
			(layers "F.Cu" "F.Mask" "F.Paste")
			(net "L12_85OHM_10INCH_DN")
		)
		(pad "2" smd circle
			(at -0.503936 -1.301496 90)
			(size 0.6604 0.6604)
			(layers "F.Cu" "F.Mask" "F.Paste")
			(net "L12_85OHM_10INCH_DP")
		)
		(pad "3" smd custom
			(at -0.00889 0.370078 90)
			(size 0.74295 0.74295)
			(layers "F.Cu" "F.Mask" "F.Paste")
			(net "GND")
			(options
				(clearance outline)
				(anchor circle)
			)
			(primitives
				(gr_poly
					(pts
						(xy -2.1209 1.4859) (xy 2.1209 1.4859) (xy 2.1209 -1.4859) (xy 1.08585 -1.4859) (xy 1.08585 -0.4699)
						(xy -1.08585 -0.4699) (xy -1.08585 -1.4859) (xy -2.1209 -1.4859)
					)
					(width 0)
					(fill yes)
				)
			)
		)
		(pad "4" thru_hole circle
			(at 1.266444 -3.851656 90)
			(size 1.4478 1.4478)
			(drill 1.0414)
			(layers "*.Cu" "*.Mask")
			(remove_unused_layers no)
			(net "GND")
			(clearance 0.1524)
			(thermal_gap 0.1524)
		)
		(pad "5" thru_hole circle
			(at -1.273556 -3.851656 90)
			(size 1.4478 1.4478)
			(drill 1.0414)
			(layers "*.Cu" "*.Mask")
			(remove_unused_layers no)
			(net "GND")
			(clearance 0.1524)
			(thermal_gap 0.1524)
		)
		(pad "6" thru_hole circle
			(at 1.266444 2.498344 90)
			(size 1.4478 1.4478)
			(drill 1.0414)
			(layers "*.Cu" "*.Mask")
			(remove_unused_layers no)
			(net "GND")
			(clearance 0.1524)
			(thermal_gap 0.1524)
		)
		(pad "7" thru_hole circle
			(at -1.273556 2.498344 90)
			(size 1.4478 1.4478)
			(drill 1.0414)
			(layers "*.Cu" "*.Mask")
			(remove_unused_layers no)
			(net "GND")
			(clearance 0.1524)
			(thermal_gap 0.1524)
		)
		(pad "8" thru_hole circle
			(at 1.27 -0.4572 90)
			(size 0.7112 0.7112)
			(drill 0.4064)
			(layers "*.Cu" "*.Mask")
			(remove_unused_layers no)
			(net "GND")
			(clearance 0.1016)
			(thermal_gap 0.1016)
		)
		(pad "9" thru_hole circle
			(at 1.27 0.762 90)
			(size 0.7112 0.7112)
			(drill 0.4064)
			(layers "*.Cu" "*.Mask")
			(remove_unused_layers no)
			(net "GND")
			(clearance 0.1016)
			(thermal_gap 0.1016)
		)
		(pad "10" thru_hole circle
			(at -0.0254 0.762 90)
			(size 0.7112 0.7112)
			(drill 0.4064)
			(layers "*.Cu" "*.Mask")
			(remove_unused_layers no)
			(net "GND")
			(clearance 0.1016)
			(thermal_gap 0.1016)
		)
		(pad "11" thru_hole circle
			(at -1.27 0.762 90)
			(size 0.7112 0.7112)
			(drill 0.4064)
			(layers "*.Cu" "*.Mask")
			(remove_unused_layers no)
			(net "GND")
			(clearance 0.1016)
			(thermal_gap 0.1016)
		)
		(pad "12" thru_hole circle
			(at -1.27 -0.4572 90)
			(size 0.7112 0.7112)
			(drill 0.4064)
			(layers "*.Cu" "*.Mask")
			(remove_unused_layers no)
			(net "GND")
			(clearance 0.1016)
			(thermal_gap 0.1016)
		)
	)
	(footprint ""
		(layer "F.Cu")
		(at 198.925434 -57.039764 90)
		(property "Reference" "EU4E1"
			(at 3.360166 -1.643634 0)
			(unlocked yes)
			(layer "F.SilkS")
			(effects
				(font
					(size 0.7874 0.5842)
					(thickness 0.1524)
				)
			)
		)
		(property "Value" ""
			(at 0 0 90)
			(layer "F.Fab")
			(effects
				(font
					(size 1.27 1.27)
				)
			)
		)
		(duplicate_pad_numbers_are_jumpers no)
		(fp_line
			(start 2.9718 -3.5052)
			(end 2.9718 3.429)
			(stroke
				(width 0.1524)
				(type default)
			)
			(layer "F.SilkS")
		)
		(fp_line
			(start -3.0099 -3.5052)
			(end 2.9718 -3.5052)
			(stroke
				(width 0.1524)
				(type default)
			)
			(layer "F.SilkS")
		)
		(fp_line
			(start 2.9718 3.429)
			(end -3.0099 3.429)
			(stroke
				(width 0.1524)
				(type default)
			)
			(layer "F.SilkS")
		)
		(fp_line
			(start -3.0099 3.429)
			(end -3.0099 -3.5052)
			(stroke
				(width 0.1524)
				(type default)
			)
			(layer "F.SilkS")
		)
		(fp_circle
			(center -3.057398 -2.678684)
			(end -3.057398 -2.551684)
			(stroke
				(width 0.254)
				(type default)
			)
			(fill no)
			(layer "F.SilkS")
		)
		(fp_poly
			(pts
				(xy -2.9972 -3.4925) (xy -2.9972 -2.6924) (xy -2.1971 -3.4925)
			)
			(stroke
				(width 0)
				(type default)
			)
			(fill yes)
			(layer "F.SilkS")
		)
		(fp_poly
			(pts
				(xy -2.549906 -3.050032) (xy -2.549906 3.050032) (xy 2.549906 3.050032) (xy 2.549906 -3.050032)
			)
			(stroke
				(width 0)
				(type default)
			)
			(fill no)
			(layer "F.CrtYd")
		)
		(fp_line
			(start 2.549906 -3.050032)
			(end 2.549906 3.050032)
			(stroke
				(width 0.1)
				(type default)
			)
			(layer "F.Fab")
		)
		(fp_line
			(start -2.549906 -3.050032)
			(end 2.549906 -3.050032)
			(stroke
				(width 0.1)
				(type default)
			)
			(layer "F.Fab")
		)
		(fp_line
			(start 2.549906 3.050032)
			(end -2.549906 3.050032)
			(stroke
				(width 0.1)
				(type default)
			)
			(layer "F.Fab")
		)
		(fp_line
			(start -2.549906 3.050032)
			(end -2.549906 -3.050032)
			(stroke
				(width 0.1)
				(type default)
			)
			(layer "F.Fab")
		)
		(fp_circle
			(center -3.057398 -2.678684)
			(end -3.057398 -2.551684)
			(stroke
				(width 0.254)
				(type default)
			)
			(fill no)
			(layer "F.Fab")
		)
		(pad "1" smd rect
			(at -2.39522 -2.279904 90)
			(size 0.7112 0.254)
			(layers "F.Cu" "F.Mask" "F.Paste")
			(net "PVCCIN_CPU0")
		)
		(pad "2" smd rect
			(at -2.39522 -1.83007 90)
			(size 0.7112 0.254)
			(layers "F.Cu" "F.Mask" "F.Paste")
			(net "GND")
		)
		(pad "3" smd rect
			(at -2.39522 -1.379982 90)
			(size 0.7112 0.254)
			(layers "F.Cu" "F.Mask" "F.Paste")
			(net "VR_PVCCIN_CPU0_PH1_VCIN")
		)
		(pad "4" smd rect
			(at -2.39522 -0.929894 90)
			(size 0.7112 0.254)
			(layers "F.Cu" "F.Mask" "F.Paste")
			(net "P5V_STBY")
		)
		(pad "5" smd rect
			(at -2.39522 -0.48006 90)
			(size 0.7112 0.254)
			(layers "F.Cu" "F.Mask" "F.Paste")
			(net "GND")
		)
		(pad "6" smd rect
			(at -2.39522 -0.029972 90)
			(size 0.7112 0.254)
			(layers "F.Cu" "F.Mask" "F.Paste")
			(net "TP_PVCCIN_CPU0_PH1_GL_0")
		)
		(pad "7" smd custom
			(at 0.016764 1.145032 90)
			(size 0.53975 0.53975)
			(layers "F.Cu" "F.Mask" "F.Paste")
			(net "GND")
			(options
				(clearance outline)
				(anchor circle)
			)
			(primitives
				(gr_poly
					(pts
						(xy -2.7051 1.0795) (xy -2.7051 -0.3683) (xy -0.9271 -0.3683) (xy -0.9271 -1.0795) (xy 2.7051 -1.0795)
						(xy 2.7051 1.0795)
					)
					(width 0)
					(fill yes)
				)
			)
		)
		(pad "10" smd rect
			(at -0.008382 2.874772 90)
			(size 4.3434 0.6096)
			(layers "F.Cu" "F.Mask" "F.Paste")
			(net "VR_PVCCIN_CPU0_PHASE1")
		)
		(pad "25" smd rect
			(at 1.548384 -1.283208 90)
			(size 2.3368 2.0066)
			(layers "F.Cu" "F.Mask" "F.Paste")
			(net "VR_FET_SW_P12V_STBY_PVCCIN_CPU0")
		)
		(pad "30" smd rect
			(at 2.050034 -2.895092 90)
			(size 0.254 0.7112)
			(layers "F.Cu" "F.Mask" "F.Paste")
			(net "VR_FET_SW_P12V_STBY_PVCCIN_CPU0")
		)
		(pad "31" smd rect
			(at 1.599946 -2.895092 90)
			(size 0.254 0.7112)
			(layers "F.Cu" "F.Mask" "F.Paste")
			(net "Net_361")
		)
		(pad "32" smd rect
			(at 1.150112 -2.895092 90)
			(size 0.254 0.7112)
			(layers "F.Cu" "F.Mask" "F.Paste")
			(net "VR_PVCCIN_CPU0_PH1_PHASE")
		)
		(pad "33" smd rect
			(at 0.700024 -2.895092 90)
			(size 0.254 0.7112)
			(layers "F.Cu" "F.Mask" "F.Paste")
			(net "VR_PVCCIN_CPU0_PH1_BOOT_R")
		)
		(pad "34" smd rect
			(at 0.249936 -2.895092 90)
			(size 0.254 0.7112)
			(layers "F.Cu" "F.Mask" "F.Paste")
			(net "VR_PVCCIN_CPU0_PWM1")
		)
		(pad "35" smd rect
			(at -0.199898 -2.895092 90)
			(size 0.254 0.7112)
			(layers "F.Cu" "F.Mask" "F.Paste")
			(net "P5V_STBY")
		)
		(pad "36" smd rect
			(at -0.649986 -2.895092 90)
			(size 0.254 0.7112)
			(layers "F.Cu" "F.Mask" "F.Paste")
			(net "A_TSENSE_PVCCIN_CPU0")
		)
		(pad "37" smd rect
			(at -1.100074 -2.895092 90)
			(size 0.254 0.7112)
			(layers "F.Cu" "F.Mask" "F.Paste")
			(net "VR_PVCCIN_CPU0_PH1_OCSET")
		)
		(pad "38" smd rect
			(at -1.549908 -2.895092 90)
			(size 0.254 0.7112)
			(layers "F.Cu" "F.Mask" "F.Paste")
			(net "ISENSE_PVCCIN_CPU0_PH1_IMON")
		)
		(pad "39" smd rect
			(at -1.999996 -2.895092 90)
			(size 0.254 0.7112)
			(layers "F.Cu" "F.Mask" "F.Paste")
			(net "VR_PVCCIN_CPU0_AIREF1")
		)
		(pad "40" smd rect
			(at -0.871728 -1.283208 90)
			(size 1.8034 2.0066)
			(layers "F.Cu" "F.Mask" "F.Paste")
			(net "GND")
		)
		(pad "41" smd rect
			(at -1.533906 0.247904 90)
			(size 0.508 0.3556)
			(layers "F.Cu" "F.Mask" "F.Paste")
			(net "TP_PVCCIN_CPU0_PH1_GL_1")
		)
	)
	(footprint ""
		(layer "F.Cu")
		(at 2.032 -69.088 180)
		(property "Reference" "R1E10"
			(at 0 0 180)
			(layer "F.SilkS")
			(hide yes)
			(effects
				(font
					(size 1.27 1.27)
				)
			)
		)
		(property "Value" ""
			(at 0 0 180)
			(layer "F.Fab")
			(effects
				(font
					(size 1.27 1.27)
				)
			)
		)
		(duplicate_pad_numbers_are_jumpers no)
		(fp_poly
			(pts
				(xy -0.2794 -0.1016) (xy 0.2794 -0.1016) (xy 0.2794 0.9906) (xy -0.2794 0.9906)
			)
			(stroke
				(width 0)
				(type default)
			)
			(fill no)
			(layer "F.CrtYd")
		)
		(fp_line
			(start 0.2794 0.9906)
			(end 0.2794 -0.1016)
			(stroke
				(width 0.1)
				(type default)
			)
			(layer "F.Fab")
		)
		(fp_line
			(start 0.2794 -0.1016)
			(end -0.2794 -0.1016)
			(stroke
				(width 0.1)
				(type default)
			)
			(layer "F.Fab")
		)
		(fp_line
			(start -0.2794 0.9906)
			(end 0.2794 0.9906)
			(stroke
				(width 0.1)
				(type default)
			)
			(layer "F.Fab")
		)
		(fp_line
			(start -0.2794 -0.1016)
			(end -0.2794 0.9906)
			(stroke
				(width 0.1)
				(type default)
			)
			(layer "F.Fab")
		)
		(pad "1" smd rect
			(at 0 0 180)
			(size 0.508 0.508)
			(layers "F.Cu" "F.Mask" "F.Paste")
			(net "P3V3_STBY")
		)
		(pad "2" smd rect
			(at 0 0.889 180)
			(size 0.508 0.508)
			(layers "F.Cu" "F.Mask" "F.Paste")
			(net "PD_TMP421_2_A1")
		)
		(zone
			(layer "F.Cu")
			(hatch none 0.5)
			(connect_pads
				(clearance 0)
			)
			(min_thickness 0.25)
			(keepout
				(tracks not_allowed)
				(vias allowed)
				(pads allowed)
				(copperpour not_allowed)
				(footprints allowed)
			)
			(placement
				(enabled no)
				(sheetname "")
			)
			(fill
				(thermal_gap 0.5)
				(thermal_bridge_width 0.5)
				(island_removal_mode 0)
			)
			(polygon
				(pts
					(xy 2.286 -69.723) (xy 1.778 -69.723) (xy 1.778 -69.342) (xy 2.286 -69.342)
				)
			)
		)
		(zone
			(layer "F.Cu")
			(hatch none 0.5)
			(connect_pads
				(clearance 0)
			)
			(min_thickness 0.25)
			(keepout
				(tracks allowed)
				(vias not_allowed)
				(pads allowed)
				(copperpour not_allowed)
				(footprints allowed)
			)
			(placement
				(enabled no)
				(sheetname "")
			)
			(fill
				(thermal_gap 0.5)
				(thermal_bridge_width 0.5)
				(island_removal_mode 0)
			)
			(polygon
				(pts
					(xy 2.286 -69.342) (xy 1.778 -69.342) (xy 1.778 -69.723) (xy 2.286 -69.723)
				)
			)
		)
	)
)
